(kicad_pcb
	(version 20260206)
	(generator "pcbnew")
	(generator_version "10.0")
	(general
		(thickness 1.6)
		(legacy_teardrops no)
	)
	(paper "A4")
	(title_block
		(title "fcb — 12433-1M.1206WZS1330.brd")
		(comment 1 "Open Vault / Knox (Wiwynn) / footprints 453-457 of 495")
	)
	(layers
		(0 "F.Cu" signal "TOP")
		(4 "In1.Cu" signal "L2GND")
		(6 "In2.Cu" signal "L3VCC")
		(2 "B.Cu" signal "BOTTOM")
		(9 "F.Adhes" user "F.Adhesive")
		(11 "B.Adhes" user "B.Adhesive")
		(13 "F.Paste" user "Package Geometry/Pastemask Top")
		(15 "B.Paste" user "Package Geometry/Pastemask Bottom")
		(5 "F.SilkS" user "Ref Des/Silkscreen Top")
		(7 "B.SilkS" user "Ref Des/Silkscreen Bottom")
		(1 "F.Mask" user "Board Geometry/Soldermask Top")
		(3 "B.Mask" user "Board Geometry/Soldermask Bottom")
		(17 "Dwgs.User" user "User.Drawings")
		(19 "Cmts.User" user "User.Comments")
		(21 "Eco1.User" user "User.Eco1")
		(23 "Eco2.User" user "User.Eco2")
		(25 "Edge.Cuts" user "Board Geometry/Outline")
		(27 "Margin" user)
		(31 "F.CrtYd" user "Package Geometry/Place Bound Top")
		(29 "B.CrtYd" user "Package Geometry/Place Bound Bottom")
		(35 "F.Fab" user "Ref Des/Assembly Top")
		(33 "B.Fab" user "Ref Des/Assembly Bottom")
	)
	(footprint ""
		(layer "F.Cu")
		(at 36.212526 -362.208826)
		(property "Reference" "PQ5"
			(at 0 0 0)
			(layer "F.SilkS")
			(hide yes)
			(effects
				(font
					(size 1.27 1.27)
				)
			)
		)
		(property "Value" "PMBS3904-1-GP"
			(at 0 -9.0932 0)
			(unlocked yes)
			(layer "F.Fab")
			(hide yes)
			(effects
				(font
					(size 1.016 1.016)
					(thickness 0.1524)
				)
			)
		)
		(property "Device Type" "SOT-23-10H44"
			(at 0 -10.6172 0)
			(unlocked yes)
			(layer "F.Fab")
			(hide yes)
			(effects
				(font
					(size 1.016 1.016)
					(thickness 0.1524)
				)
			)
		)
		(duplicate_pad_numbers_are_jumpers no)
		(fp_line
			(start -1.7526 1.8796)
			(end -1.7526 0.9906)
			(stroke
				(width 0.3302)
				(type default)
			)
			(layer "F.SilkS")
		)
		(fp_line
			(start -1.651 -1.778)
			(end -1.651 1.778)
			(stroke
				(width 0.1524)
				(type default)
			)
			(layer "F.SilkS")
		)
		(fp_line
			(start -1.651 1.778)
			(end 1.651 1.778)
			(stroke
				(width 0.1524)
				(type default)
			)
			(layer "F.SilkS")
		)
		(fp_line
			(start -1.279398 2.152142)
			(end -0.9906 1.86309)
			(stroke
				(width 0.0127)
				(type default)
			)
			(layer "F.SilkS")
		)
		(fp_line
			(start -1.279144 2.15265)
			(end -0.701294 2.15265)
			(stroke
				(width 0.0127)
				(type default)
			)
			(layer "F.SilkS")
		)
		(fp_line
			(start -1.260856 2.1336)
			(end -0.720344 2.1336)
			(stroke
				(width 0.0127)
				(type default)
			)
			(layer "F.SilkS")
		)
		(fp_line
			(start -1.251458 2.124202)
			(end -0.729996 2.124202)
			(stroke
				(width 0.0127)
				(type default)
			)
			(layer "F.SilkS")
		)
		(fp_line
			(start -1.241806 2.11455)
			(end -0.739394 2.11455)
			(stroke
				(width 0.0127)
				(type default)
			)
			(layer "F.SilkS")
		)
		(fp_line
			(start -1.232408 2.105152)
			(end -0.749046 2.105152)
			(stroke
				(width 0.0127)
				(type default)
			)
			(layer "F.SilkS")
		)
		(fp_line
			(start -1.222756 2.0955)
			(end -0.758444 2.0955)
			(stroke
				(width 0.0127)
				(type default)
			)
			(layer "F.SilkS")
		)
		(fp_line
			(start -1.213358 2.086102)
			(end -0.768096 2.086102)
			(stroke
				(width 0.0127)
				(type default)
			)
			(layer "F.SilkS")
		)
		(fp_line
			(start -1.203706 2.07645)
			(end -0.777494 2.07645)
			(stroke
				(width 0.0127)
				(type default)
			)
			(layer "F.SilkS")
		)
		(fp_line
			(start -1.194308 2.067052)
			(end -0.787146 2.067052)
			(stroke
				(width 0.0127)
				(type default)
			)
			(layer "F.SilkS")
		)
		(fp_line
			(start -1.184656 2.0574)
			(end -0.796544 2.0574)
			(stroke
				(width 0.0127)
				(type default)
			)
			(layer "F.SilkS")
		)
		(fp_line
			(start -1.175258 2.048002)
			(end -0.806196 2.048002)
			(stroke
				(width 0.0127)
				(type default)
			)
			(layer "F.SilkS")
		)
		(fp_line
			(start -1.165606 2.03835)
			(end -0.815594 2.03835)
			(stroke
				(width 0.0127)
				(type default)
			)
			(layer "F.SilkS")
		)
		(fp_line
			(start -1.156208 2.028952)
			(end -0.825246 2.028952)
			(stroke
				(width 0.0127)
				(type default)
			)
			(layer "F.SilkS")
		)
		(fp_line
			(start -1.146556 2.0193)
			(end -0.834644 2.0193)
			(stroke
				(width 0.0127)
				(type default)
			)
			(layer "F.SilkS")
		)
		(fp_line
			(start -1.137158 2.009902)
			(end -0.844296 2.009902)
			(stroke
				(width 0.0127)
				(type default)
			)
			(layer "F.SilkS")
		)
		(fp_line
			(start -1.127506 2.00025)
			(end -0.853694 2.00025)
			(stroke
				(width 0.0127)
				(type default)
			)
			(layer "F.SilkS")
		)
		(fp_line
			(start -1.118108 1.990852)
			(end -0.863346 1.990852)
			(stroke
				(width 0.0127)
				(type default)
			)
			(layer "F.SilkS")
		)
		(fp_line
			(start -1.108456 1.9812)
			(end -0.872744 1.9812)
			(stroke
				(width 0.0127)
				(type default)
			)
			(layer "F.SilkS")
		)
		(fp_line
			(start -1.099058 1.971802)
			(end -0.882396 1.971802)
			(stroke
				(width 0.0127)
				(type default)
			)
			(layer "F.SilkS")
		)
		(fp_line
			(start -1.089406 1.96215)
			(end -0.891794 1.96215)
			(stroke
				(width 0.0127)
				(type default)
			)
			(layer "F.SilkS")
		)
		(fp_line
			(start -1.080008 1.952752)
			(end -0.901446 1.952752)
			(stroke
				(width 0.0127)
				(type default)
			)
			(layer "F.SilkS")
		)
		(fp_line
			(start -1.070356 1.9431)
			(end -0.910844 1.9431)
			(stroke
				(width 0.0127)
				(type default)
			)
			(layer "F.SilkS")
		)
		(fp_line
			(start -1.060958 1.933702)
			(end -0.920496 1.933702)
			(stroke
				(width 0.0127)
				(type default)
			)
			(layer "F.SilkS")
		)
		(fp_line
			(start -1.051306 1.92405)
			(end -0.929894 1.92405)
			(stroke
				(width 0.0127)
				(type default)
			)
			(layer "F.SilkS")
		)
		(fp_line
			(start -1.041908 1.914652)
			(end -0.939546 1.914652)
			(stroke
				(width 0.0127)
				(type default)
			)
			(layer "F.SilkS")
		)
		(fp_line
			(start -1.032256 1.905)
			(end -0.948944 1.905)
			(stroke
				(width 0.0127)
				(type default)
			)
			(layer "F.SilkS")
		)
		(fp_line
			(start -1.022858 1.895602)
			(end -0.958596 1.895602)
			(stroke
				(width 0.0127)
				(type default)
			)
			(layer "F.SilkS")
		)
		(fp_line
			(start -1.013206 1.88595)
			(end -0.967994 1.88595)
			(stroke
				(width 0.0127)
				(type default)
			)
			(layer "F.SilkS")
		)
		(fp_line
			(start -1.003808 1.876552)
			(end -0.977646 1.876552)
			(stroke
				(width 0.0127)
				(type default)
			)
			(layer "F.SilkS")
		)
		(fp_line
			(start -0.994156 1.8669)
			(end -0.987044 1.8669)
			(stroke
				(width 0.0127)
				(type default)
			)
			(layer "F.SilkS")
		)
		(fp_line
			(start -0.9906 1.86309)
			(end -0.701294 2.15265)
			(stroke
				(width 0.0127)
				(type default)
			)
			(layer "F.SilkS")
		)
		(fp_line
			(start -0.719074 2.145538)
			(end -1.265936 2.14122)
			(stroke
				(width 0.0127)
				(type default)
			)
			(layer "F.SilkS")
		)
		(fp_line
			(start -0.71628 2.15265)
			(end -1.26492 2.15265)
			(stroke
				(width 0.0127)
				(type default)
			)
			(layer "F.SilkS")
		)
		(fp_line
			(start -0.635 1.8796)
			(end -1.7526 1.8796)
			(stroke
				(width 0.3302)
				(type default)
			)
			(layer "F.SilkS")
		)
		(fp_line
			(start 1.651 -1.778)
			(end -1.651 -1.778)
			(stroke
				(width 0.1524)
				(type default)
			)
			(layer "F.SilkS")
		)
		(fp_line
			(start 1.651 1.778)
			(end 1.651 -1.778)
			(stroke
				(width 0.1524)
				(type default)
			)
			(layer "F.SilkS")
		)
		(fp_poly
			(pts
				(xy -1.285748 2.159) (xy -1.285748 1.8796) (xy -1.778 1.8796) (xy -1.778 -1.8796) (xy 1.778 -1.8796)
				(xy 1.778 1.8796) (xy -0.694944 1.8796) (xy -0.694944 2.159)
			)
			(stroke
				(width 0)
				(type default)
			)
			(fill no)
			(layer "F.CrtYd")
		)
		(fp_poly
			(pts
				(xy -1.285748 2.159) (xy -1.285748 1.8796) (xy -1.778 1.8796) (xy -1.778 -1.8796) (xy 1.778 -1.8796)
				(xy 1.778 1.8796) (xy -0.694944 1.8796) (xy -0.694944 2.159)
			)
			(stroke
				(width 0)
				(type default)
			)
			(fill no)
			(layer "F.Fab")
		)
		(pad "1" smd rect
			(at -0.98425 0.9525)
			(size 0.762 1.143)
			(layers "F.Cu" "F.Mask" "F.Paste")
			(net "TEMP_ALM#_REVERSE_R")
		)
		(pad "2" smd rect
			(at 0.98425 0.9525)
			(size 0.762 1.143)
			(layers "F.Cu" "F.Mask" "F.Paste")
			(net "GND")
		)
		(pad "3" smd rect
			(at 0 -0.9525)
			(size 0.762 1.143)
			(layers "F.Cu" "F.Mask" "F.Paste")
			(net "ADM1276_LATCH_B")
		)
	)
	(footprint ""
		(layer "F.Cu")
		(at 21.7424 -21.8948)
		(property "Reference" "F1"
			(at 0 0 0)
			(layer "F.SilkS")
			(hide yes)
			(effects
				(font
					(size 1.27 1.27)
				)
			)
		)
		(property "Value" "FUSE-3A15V-GP"
			(at 0.2286 -10.5918 0)
			(unlocked yes)
			(layer "F.Fab")
			(hide yes)
			(effects
				(font
					(size 1.016 1.016)
					(thickness 0.1524)
				)
			)
		)
		(property "Device Type" "FUSE-7452-UH50"
			(at 0.2286 -12.4968 0)
			(unlocked yes)
			(layer "F.Fab")
			(hide yes)
			(effects
				(font
					(size 1.016 1.016)
					(thickness 0.1524)
				)
			)
		)
		(duplicate_pad_numbers_are_jumpers no)
		(fp_line
			(start -4.9276 -2.921)
			(end 4.9276 -2.921)
			(stroke
				(width 0.1524)
				(type default)
			)
			(layer "F.SilkS")
		)
		(fp_line
			(start -4.9276 2.921)
			(end -4.9276 -2.921)
			(stroke
				(width 0.1524)
				(type default)
			)
			(layer "F.SilkS")
		)
		(fp_line
			(start 4.9276 -2.921)
			(end 4.9276 2.921)
			(stroke
				(width 0.1524)
				(type default)
			)
			(layer "F.SilkS")
		)
		(fp_line
			(start 4.9276 2.921)
			(end -4.9276 2.921)
			(stroke
				(width 0.1524)
				(type default)
			)
			(layer "F.SilkS")
		)
		(fp_poly
			(pts
				(xy -5.08 3.0988) (xy 5.08 3.0988) (xy 5.08 -3.0988) (xy -5.08 -3.0988)
			)
			(stroke
				(width 0)
				(type default)
			)
			(fill no)
			(layer "F.CrtYd")
		)
		(fp_poly
			(pts
				(xy -5.08 -3.0988) (xy 5.08 -3.0988) (xy 5.08 3.0988) (xy -5.08 3.0988)
			)
			(stroke
				(width 0)
				(type default)
			)
			(fill no)
			(layer "F.Fab")
		)
		(pad "1" smd rect
			(at -3.4036 0)
			(size 2.2098 5.2832)
			(layers "F.Cu" "F.Mask" "F.Paste")
			(net "P12V_FAN6")
		)
		(pad "2" smd rect
			(at 3.4036 0)
			(size 2.2098 5.2832)
			(layers "F.Cu" "F.Mask" "F.Paste")
			(net "P12V")
		)
	)
	(footprint ""
		(layer "F.Cu")
		(at 24.4602 -142.367)
		(property "Reference" "PC96"
			(at 0 0 0)
			(layer "F.SilkS")
			(hide yes)
			(effects
				(font
					(size 1.27 1.27)
				)
			)
		)
		(property "Value" "SCD1U50V3KX-GP"
			(at 0 -2.8194 0)
			(unlocked yes)
			(layer "F.Fab")
			(hide yes)
			(effects
				(font
					(size 1.016 1.016)
					(thickness 0.1524)
				)
			)
		)
		(property "Device Type" "C603H36"
			(at 0 -4.3434 0)
			(unlocked yes)
			(layer "F.Fab")
			(hide yes)
			(effects
				(font
					(size 1.016 1.016)
					(thickness 0.1524)
				)
			)
		)
		(duplicate_pad_numbers_are_jumpers no)
		(fp_line
			(start 0.508 0)
			(end -0.508 0)
			(stroke
				(width 0.2032)
				(type default)
			)
			(layer "F.SilkS")
		)
		(fp_rect
			(start -0.5842 1.3335)
			(end 0.5842 -1.3335)
			(stroke
				(width 0)
				(type default)
			)
			(fill no)
			(layer "F.CrtYd")
		)
		(fp_rect
			(start -0.5842 1.3335)
			(end 0.5842 -1.3335)
			(stroke
				(width 0)
				(type default)
			)
			(fill no)
			(layer "F.Fab")
		)
		(pad "1" smd custom
			(at 0 -0.762)
			(size 0.2159 0.2159)
			(layers "F.Cu" "F.Mask" "F.Paste")
			(net "P12VU_2490_EN_2")
			(options
				(clearance outline)
				(anchor circle)
			)
			(primitives
				(gr_poly
					(pts
						(arc
							(start -0.3302 -0.4318)
							(mid -0.402042 -0.402042)
							(end -0.4318 -0.3302)
						)
						(arc
							(start -0.4318 0.3302)
							(mid -0.402042 0.402042)
							(end -0.3302 0.4318)
						)
						(arc
							(start 0.3302 0.4318)
							(mid 0.402042 0.402042)
							(end 0.4318 0.3302)
						)
						(arc
							(start 0.4318 -0.3302)
							(mid 0.402042 -0.402042)
							(end 0.3302 -0.4318)
						)
					)
					(width 0)
					(fill yes)
				)
			)
		)
		(pad "2" smd custom
			(at 0 0.762)
			(size 0.2159 0.2159)
			(layers "F.Cu" "F.Mask" "F.Paste")
			(net "GND")
			(options
				(clearance outline)
				(anchor circle)
			)
			(primitives
				(gr_poly
					(pts
						(arc
							(start -0.3302 -0.4318)
							(mid -0.402042 -0.402042)
							(end -0.4318 -0.3302)
						)
						(arc
							(start -0.4318 0.3302)
							(mid -0.402042 0.402042)
							(end -0.3302 0.4318)
						)
						(arc
							(start 0.3302 0.4318)
							(mid 0.402042 0.402042)
							(end 0.4318 0.3302)
						)
						(arc
							(start 0.4318 -0.3302)
							(mid 0.402042 -0.402042)
							(end 0.3302 -0.4318)
						)
					)
					(width 0)
					(fill yes)
				)
			)
		)
	)
	(footprint ""
		(layer "F.Cu")
		(at 22.5044 -136.6012 90)
		(property "Reference" "PC87"
			(at 0 0 90)
			(layer "F.SilkS")
			(hide yes)
			(effects
				(font
					(size 1.27 1.27)
				)
			)
		)
		(property "Value" "SC220P50V2KX-3GP"
			(at 1.1811 -2.7051 90)
			(unlocked yes)
			(layer "F.Fab")
			(hide yes)
			(effects
				(font
					(size 1.016 1.016)
					(thickness 0.1524)
				)
			)
		)
		(property "Device Type" "C402H22"
			(at 1.1811 -4.2291 90)
			(unlocked yes)
			(layer "F.Fab")
			(hide yes)
			(effects
				(font
					(size 1.016 1.016)
					(thickness 0.1524)
				)
			)
		)
		(duplicate_pad_numbers_are_jumpers no)
		(fp_rect
			(start -0.4318 0.9525)
			(end 0.4318 -0.9525)
			(stroke
				(width 0)
				(type default)
			)
			(fill no)
			(layer "F.CrtYd")
		)
		(fp_rect
			(start -0.4318 0.9525)
			(end 0.4318 -0.9525)
			(stroke
				(width 0)
				(type default)
			)
			(fill no)
			(layer "F.Fab")
		)
		(pad "1" smd custom
			(at 0 -0.4445 90)
			(size 0.1524 0.1524)
			(layers "F.Cu" "F.Mask" "F.Paste")
			(net "P12VU_2490_SENSE")
			(options
				(clearance outline)
				(anchor circle)
			)
			(primitives
				(gr_poly
					(pts
						(arc
							(start 0.3048 -0.2032)
							(mid 0.275042 -0.275042)
							(end 0.2032 -0.3048)
						)
						(arc
							(start -0.2032 -0.3048)
							(mid -0.275042 -0.275042)
							(end -0.3048 -0.2032)
						)
						(arc
							(start -0.3048 0.2032)
							(mid -0.275042 0.275042)
							(end -0.2032 0.3048)
						)
						(arc
							(start 0.2032 0.3048)
							(mid 0.275042 0.275042)
							(end 0.3048 0.2032)
						)
					)
					(width 0)
					(fill yes)
				)
			)
		)
		(pad "2" smd custom
			(at 0 0.4445 90)
			(size 0.1524 0.1524)
			(layers "F.Cu" "F.Mask" "F.Paste")
			(net "P12VU_2490_VCC")
			(options
				(clearance outline)
				(anchor circle)
			)
			(primitives
				(gr_poly
					(pts
						(arc
							(start 0.3048 -0.2032)
							(mid 0.275042 -0.275042)
							(end 0.2032 -0.3048)
						)
						(arc
							(start -0.2032 -0.3048)
							(mid -0.275042 -0.275042)
							(end -0.3048 -0.2032)
						)
						(arc
							(start -0.3048 0.2032)
							(mid -0.275042 0.275042)
							(end -0.2032 0.3048)
						)
						(arc
							(start 0.2032 0.3048)
							(mid 0.275042 0.275042)
							(end 0.3048 0.2032)
						)
					)
					(width 0)
					(fill yes)
				)
			)
		)
	)
	(footprint ""
		(layer "F.Cu")
		(at 16.128492 -285.014162 180)
		(property "Reference" "R93"
			(at 0 0 180)
			(layer "F.SilkS")
			(hide yes)
			(effects
				(font
					(size 1.27 1.27)
				)
			)
		)
		(property "Value" "4K7R2F-GP"
			(at 0.064008 -3.993896 180)
			(unlocked yes)
			(layer "F.Fab")
			(hide yes)
			(effects
				(font
					(size 1.016 1.016)
					(thickness 0.1524)
				)
			)
		)
		(property "Device Type" "R402H16"
			(at 0.064008 -5.517896 180)
			(unlocked yes)
			(layer "F.Fab")
			(hide yes)
			(effects
				(font
					(size 1.016 1.016)
					(thickness 0.1524)
				)
			)
		)
		(duplicate_pad_numbers_are_jumpers no)
		(fp_line
			(start 0.508 -0.9398)
			(end -0.508 -0.9398)
			(stroke
				(width 0.1524)
				(type default)
			)
			(layer "F.SilkS")
		)
		(fp_line
			(start -0.508 -0.9398)
			(end -0.508 0.9398)
			(stroke
				(width 0.1524)
				(type default)
			)
			(layer "F.SilkS")
		)
		(fp_rect
			(start -0.508 0.9398)
			(end 0.508 -0.9398)
			(stroke
				(width 0)
				(type default)
			)
			(fill no)
			(layer "F.CrtYd")
		)
		(fp_rect
			(start -0.508 0.9398)
			(end 0.508 -0.9398)
			(stroke
				(width 0)
				(type default)
			)
			(fill no)
			(layer "F.Fab")
		)
		(pad "1" smd custom
			(at 0 -0.4445 180)
			(size 0.1397 0.1397)
			(layers "F.Cu" "F.Mask" "F.Paste")
			(net "P12V")
			(options
				(clearance outline)
				(anchor circle)
			)
			(primitives
				(gr_poly
					(pts
						(arc
							(start -0.1778 -0.2794)
							(mid -0.249642 -0.249642)
							(end -0.2794 -0.1778)
						)
						(arc
							(start -0.2794 0.1778)
							(mid -0.249642 0.249642)
							(end -0.1778 0.2794)
						)
						(arc
							(start 0.1778 0.2794)
							(mid 0.249642 0.249642)
							(end 0.2794 0.1778)
						)
						(arc
							(start 0.2794 -0.1778)
							(mid 0.249642 -0.249642)
							(end 0.1778 -0.2794)
						)
					)
					(width 0)
					(fill yes)
				)
			)
		)
		(pad "2" smd custom
			(at 0 0.4445 180)
			(size 0.1397 0.1397)
			(layers "F.Cu" "F.Mask" "F.Paste")
			(net "FAN_TACH3")
			(options
				(clearance outline)
				(anchor circle)
			)
			(primitives
				(gr_poly
					(pts
						(arc
							(start -0.1778 -0.2794)
							(mid -0.249642 -0.249642)
							(end -0.2794 -0.1778)
						)
						(arc
							(start -0.2794 0.1778)
							(mid -0.249642 0.249642)
							(end -0.1778 0.2794)
						)
						(arc
							(start 0.1778 0.2794)
							(mid 0.249642 0.249642)
							(end 0.2794 0.1778)
						)
						(arc
							(start 0.2794 -0.1778)
							(mid 0.249642 -0.249642)
							(end 0.1778 -0.2794)
						)
					)
					(width 0)
					(fill yes)
				)
			)
		)
	)
)
